pagename "google_title_block_c"
version 1
lowerleft (-8000, 0)
upperright (0, 5000)
xmark "1" -1000
xmark "2" -3000
xmark "3" -5000
xmark "4" -7000
ymark "A" 1250
ymark "B" 3750
excludearea "1" (-3000,0) (0,1000)
excludearea "2" (-3750,4550) (0,5000)
{schrep "basenets" (1,20)(2,35)(3,25)}
schrep "basenets" (1,20)(3,21)
{schrep "netsbypage" (1,7)(2,15)(3,20)(4,15)(5,21)}
schrep "netsbypage" (1,5)(2,20)(5,21)
schrep "synonyms" (1,15)(2,20)(3,25)(4,21)
{schrep "crefparts" (1,10)(2,20)(3,50)}
schrep "crefparts" (1,7)(2,20)(3,20)


pagename "google_title_block_c"
version 2
lowerleft (-8000, 0)
upperright (0, 5000)
xmark "1" -1000
xmark "2" -3000
xmark "3" -5000
xmark "4" -7000
ymark "A" 1250
ymark "B" 3750
excludearea "1" (-3000,0) (0,1000)
excludearea "2" (-3750,4550) (0,5000)
{schrep "basenets" (1,20)(2,35)(3,25)}
schrep "basenets" (1,20)(3,21)
{schrep "netsbypage" (1,7)(2,15)(3,20)(4,15)(5,21)}
schrep "netsbypage" (1,5)(2,20)(5,21)
schrep "synonyms" (1,15)(2,20)(3,25)(4,21)
{schrep "crefparts" (1,10)(2,20)(3,50)}
schrep "crefparts" (1,7)(2,20)(3,20)


pagename "google_title_block_c"
version 3
lowerleft (-8000, 0)
upperright (0, 5000)
xmark "1" -1000
xmark "2" -3000
xmark "3" -5000
xmark "4" -7000
ymark "A" 1250
ymark "B" 3750
excludearea "1" (-3000,0) (0,1000)
excludearea "2" (-3750,4550) (0,5000)
{schrep "basenets" (1,20)(2,35)(3,25)}
schrep "basenets" (1,20)(3,21)
{schrep "netsbypage" (1,7)(2,15)(3,20)(4,15)(5,21)}
schrep "netsbypage" (1,5)(2,20)(5,21)
schrep "synonyms" (1,15)(2,20)(3,25)(4,21)
{schrep "crefparts" (1,10)(2,20)(3,50)}
schrep "crefparts" (1,7)(2,20)(3,20)
pagename "APD_OR_SCH"
version 1
lowerleft (-8000, 200)
upperright (0, 5000)
xmark "1" -500
xmark "2" -1500
xmark "3" -2500
xmark "4" -3500
xmark "5" -4500
xmark "6" -5500
xmark "7" -6500
xmark "8" -7500
ymark "A" 1000
ymark "B" 2200
ymark "C" 3300
ymark "D" 4500
{schrep "basenets" (1,20)(2,35)(3,25)}
schrep "basenets" (1,20)(3,25)
schrep "netsbypage" (1,7)(2,15)(3,20)(4,15)(5,21)
schrep "synonyms" (1,15)(2,20)(3,25)(4,21)
{schrep "crefparts" (1,10)(2,20)(3,50)}
schrep "crefparts" (1,10)(2,20)(3,20)


pagename "empty_title_block_c"
version 1
lowerleft (-8000, 0)
upperright (0, 5000)
xmark "1" -1000
xmark "2" -3000
xmark "3" -5000
xmark "4" -7000
ymark "A" 1250
ymark "B" 3750
excludearea "1" (-3000,0) (0,1000)
excludearea "2" (-3750,4550) (0,5000)
{schrep "basenets" (1,20)(2,35)(3,25)}
schrep "basenets" (1,20)(3,21)
{schrep "netsbypage" (1,7)(2,15)(3,20)(4,15)(5,21)}
schrep "netsbypage" (1,5)(2,20)(5,21)
schrep "synonyms" (1,15)(2,20)(3,25)(4,21)
{schrep "crefparts" (1,10)(2,20)(3,50)}
schrep "crefparts" (1,7)(2,20)(3,20)




pagename "empty_title_block_c"
version 2
lowerleft (-8000, 0)
upperright (0, 5000)
xmark "1" -1000
xmark "2" -3000
xmark "3" -5000
xmark "4" -7000
ymark "A" 1250
ymark "B" 3750
excludearea "1" (-3000,0) (0,1000)
excludearea "2" (-3750,4550) (0,5000)
{schrep "basenets" (1,20)(2,35)(3,25)}
schrep "basenets" (1,20)(3,21)
{schrep "netsbypage" (1,7)(2,15)(3,20)(4,15)(5,21)}
schrep "netsbypage" (1,5)(2,20)(5,21)
schrep "synonyms" (1,15)(2,20)(3,25)(4,21)
{schrep "crefparts" (1,10)(2,20)(3,50)}
schrep "crefparts" (1,7)(2,20)(3,20)


pagename "empty_title_block_c"
version 3
lowerleft (-8000, 0)
upperright (0, 5000)
xmark "1" -1000
xmark "2" -3000
xmark "3" -5000
xmark "4" -7000
ymark "A" 1250
ymark "B" 3750
excludearea "1" (-3000,0) (0,1000)
excludearea "2" (-3750,4550) (0,5000)
{schrep "basenets" (1,20)(2,35)(3,25)}
schrep "basenets" (1,20)(3,21)
{schrep "netsbypage" (1,7)(2,15)(3,20)(4,15)(5,21)}
schrep "netsbypage" (1,5)(2,20)(5,21)
schrep "synonyms" (1,15)(2,20)(3,25)(4,21)
{schrep "crefparts" (1,10)(2,20)(3,50)}
schrep "crefparts" (1,7)(2,20)(3,20)
pagename "APD_OR_SCH"
version 1
lowerleft (-8000, 200)
upperright (0, 5000)
xmark "1" -500
xmark "2" -1500
xmark "3" -2500
xmark "4" -3500
xmark "5" -4500
xmark "6" -5500
xmark "7" -6500
xmark "8" -7500
ymark "A" 1000
ymark "B" 2200
ymark "C" 3300
ymark "D" 4500
{schrep "basenets" (1,20)(2,35)(3,25)}
schrep "basenets" (1,20)(3,25)
schrep "netsbypage" (1,7)(2,15)(3,20)(4,15)(5,21)
schrep "synonyms" (1,15)(2,20)(3,25)(4,21)
{schrep "crefparts" (1,10)(2,20)(3,50)}
schrep "crefparts" (1,10)(2,20)(3,20)





pagename "quanta_title_block_b"
version 1
lowerleft (-8000, 0)
upperright (0, 5000)
xmark "1" -1000
xmark "2" -3000
xmark "3" -5000
xmark "4" -7000
ymark "A" 1250
ymark "B" 3750
excludearea "1" (-8000,0) (0,400)
{schrep "basenets" (1,20)(2,35)(3,25)}
schrep "basenets" (1,20)(3,21)
{schrep "netsbypage" (1,7)(2,15)(3,20)(4,15)(5,21)}
schrep "netsbypage" (1,5)(2,20)(5,21)
schrep "synonyms" (1,15)(2,20)(3,25)(4,21)
{schrep "crefparts" (1,10)(2,20)(3,50)}
schrep "crefparts" (1,7)(2,20)(3,20)

pagename "quanta_title_block_b"
version 2
lowerleft (-8000, 0)
upperright (0, 5000)
xmark "1" -1000
xmark "2" -3000
xmark "3" -5000
xmark "4" -7000
ymark "A" 1250
ymark "B" 3750
excludearea "1" (-3000,0) (0,1000)
excludearea "2" (-3750,4550) (0,5000)
{schrep "basenets" (1,20)(2,35)(3,25)}
schrep "basenets" (1,20)(3,21)
{schrep "netsbypage" (1,7)(2,15)(3,20)(4,15)(5,21)}
schrep "netsbypage" (1,5)(2,20)(5,21)
schrep "synonyms" (1,15)(2,20)(3,25)(4,21)
{schrep "crefparts" (1,10)(2,20)(3,50)}
schrep "crefparts" (1,7)(2,20)(3,20)

pagename "quanta_title_block_b"
version 3
lowerleft (-8000, 0)
upperright (0, 5000)
xmark "1" -1000
xmark "2" -3000
xmark "3" -5000
xmark "4" -7000
ymark "A" 1250
ymark "B" 3750
excludearea "1" (-3000,0) (0,1000)
excludearea "2" (-3750,4550) (0,5000)
{schrep "basenets" (1,20)(2,35)(3,25)}
schrep "basenets" (1,20)(3,21)
{schrep "netsbypage" (1,7)(2,15)(3,20)(4,15)(5,21)}
schrep "netsbypage" (1,5)(2,20)(5,21)
schrep "synonyms" (1,15)(2,20)(3,25)(4,21)
{schrep "crefparts" (1,10)(2,20)(3,50)}
schrep "crefparts" (1,7)(2,20)(3,20)
pagename "APD_OR_SCH"
version 1
lowerleft (-8000, 200)
upperright (0, 5000)
xmark "1" -500
xmark "2" -1500
xmark "3" -2500
xmark "4" -3500
xmark "5" -4500
xmark "6" -5500
xmark "7" -6500
xmark "8" -7500
ymark "A" 1000
ymark "B" 2200
ymark "C" 3300
ymark "D" 4500
{schrep "basenets" (1,20)(2,35)(3,25)}
schrep "basenets" (1,20)(3,25)
schrep "netsbypage" (1,7)(2,15)(3,20)(4,15)(5,21)
schrep "synonyms" (1,15)(2,20)(3,25)(4,21)
{schrep "crefparts" (1,10)(2,20)(3,50)}
schrep "crefparts" (1,10)(2,20)(3,20)


pagename "quanta_title_block_c"
version 1
lowerleft (-8000, 0)
upperright (0, 5000)
xmark "1" -1000
xmark "2" -3000
xmark "3" -5000
xmark "4" -7000
ymark "A" 1250
ymark "B" 3750
excludearea "1" (-8000,0) (0,400)
{schrep "basenets" (1,20)(2,35)(3,25)}
schrep "basenets" (1,20)(3,21)
{schrep "netsbypage" (1,7)(2,15)(3,20)(4,15)(5,21)}
schrep "netsbypage" (1,5)(2,20)(5,21)
schrep "synonyms" (1,15)(2,20)(3,25)(4,21)
{schrep "crefparts" (1,10)(2,20)(3,50)}
schrep "crefparts" (1,7)(2,20)(3,20)



pagename "quanta_title_block_c"
version 2
lowerleft (-8000, 0)
upperright (0, 5000)
xmark "1" -1000
xmark "2" -3000
xmark "3" -5000
xmark "4" -7000
ymark "A" 1250
ymark "B" 3750
excludearea "1" (-3000,0) (0,1000)
excludearea "2" (-3750,4550) (0,5000)
{schrep "basenets" (1,20)(2,35)(3,25)}
schrep "basenets" (1,20)(3,21)
{schrep "netsbypage" (1,7)(2,15)(3,20)(4,15)(5,21)}
schrep "netsbypage" (1,5)(2,20)(5,21)
schrep "synonyms" (1,15)(2,20)(3,25)(4,21)
{schrep "crefparts" (1,10)(2,20)(3,50)}
schrep "crefparts" (1,7)(2,20)(3,20)




pagename "quanta_title_block_c"
version 3
lowerleft (-8000, 0)
upperright (0, 5000)
xmark "1" -1000
xmark "2" -3000
xmark "3" -5000
xmark "4" -7000
ymark "A" 1250
ymark "B" 3750
excludearea "1" (-3000,0) (0,1000)
excludearea "2" (-3750,4550) (0,5000)
{schrep "basenets" (1,20)(2,35)(3,25)}
schrep "basenets" (1,20)(3,21)
{schrep "netsbypage" (1,7)(2,15)(3,20)(4,15)(5,21)}
schrep "netsbypage" (1,5)(2,20)(5,21)
schrep "synonyms" (1,15)(2,20)(3,25)(4,21)
{schrep "crefparts" (1,10)(2,20)(3,50)}
schrep "crefparts" (1,7)(2,20)(3,20)
pagename "APD_OR_SCH"
version 1
lowerleft (-8000, 200)
upperright (0, 5000)
xmark "1" -500
xmark "2" -1500
xmark "3" -2500
xmark "4" -3500
xmark "5" -4500
xmark "6" -5500
xmark "7" -6500
xmark "8" -7500
ymark "A" 1000
ymark "B" 2200
ymark "C" 3300
ymark "D" 4500
{schrep "basenets" (1,20)(2,35)(3,25)}
schrep "basenets" (1,20)(3,25)
schrep "netsbypage" (1,7)(2,15)(3,20)(4,15)(5,21)
schrep "synonyms" (1,15)(2,20)(3,25)(4,21)
{schrep "crefparts" (1,10)(2,20)(3,50)}
schrep "crefparts" (1,10)(2,20)(3,20)




pagename "C-1 SIZE PAGE"
version 1
lowerleft (-9540, 0)
upperright (-90, 6740)
xmark "1" -830
xmark "2" -2075
xmark "3" -3420
xmark "4" -4775
xmark "5" -6130
xmark "6" -7440
xmark "7" -8830
ymark "A" 700
ymark "B" 2030
ymark "C" 3370
ymark "D" 4730
ymark "E" 6075
excludearea "1" (-3990,100) (-80,880)

pagename "C-1 SIZE PAGE"
version 2
lowerleft (-9540, 0)
upperright (-90, 6740)
xmark "1" -830
xmark "2" -2075
xmark "3" -3420
xmark "4" -4775
xmark "5" -6130
xmark "6" -7440
xmark "7" -8830
ymark "A" 700
ymark "B" 2030
ymark "C" 3370
ymark "D" 4730
ymark "E" 6075
excludearea "1" (-3990,100) (-80,880)

pagename "INTEL_CORP_BPAGE"
version 1
lowerleft (-8000, 0)
upperright (0, 5000)
xmark "1" -1000
xmark "2" -3000
xmark "3" -5000
xmark "4" -7000
ymark "A" 1250
ymark "B" 3750
excludearea "1" (-8000,0) (0,400)
{schrep "basenets" (1,20)(2,35)(3,25)}
schrep "basenets" (1,20)(3,21)
{schrep "netsbypage" (1,7)(2,15)(3,20)(4,15)(5,21)}
schrep "netsbypage" (1,5)(2,20)(5,21)
schrep "synonyms" (1,15)(2,20)(3,25)(4,21)
{schrep "crefparts" (1,10)(2,20)(3,50)}
schrep "crefparts" (1,7)(2,20)(3,20)

pagename "INTEL_CORP_BPAGE"
version 2
lowerleft (-8000, 0)
upperright (0, 5000)
xmark "1" -1000
xmark "2" -3000
xmark "3" -5000
xmark "4" -7000
ymark "A" 1250
ymark "B" 3750
excludearea "1" (-3000,0) (0,1000)
excludearea "2" (-3750,4550) (0,5000)
{schrep "basenets" (1,20)(2,35)(3,25)}
schrep "basenets" (1,20)(3,21)
{schrep "netsbypage" (1,7)(2,15)(3,20)(4,15)(5,21)}
schrep "netsbypage" (1,5)(2,20)(5,21)
schrep "synonyms" (1,15)(2,20)(3,25)(4,21)
{schrep "crefparts" (1,10)(2,20)(3,50)}
schrep "crefparts" (1,7)(2,20)(3,20)
pagename "APD_OR_SCH"
version 1
lowerleft (-8000, 200)
upperright (0, 5000)
xmark "1" -500
xmark "2" -1500
xmark "3" -2500
xmark "4" -3500
xmark "5" -4500
xmark "6" -5500
xmark "7" -6500
xmark "8" -7500
ymark "A" 1000
ymark "B" 2200
ymark "C" 3300
ymark "D" 4500
{schrep "basenets" (1,20)(2,35)(3,25)}
schrep "basenets" (1,20)(3,25)
schrep "netsbypage" (1,7)(2,15)(3,20)(4,15)(5,21)
schrep "synonyms" (1,15)(2,20)(3,25)(4,21)
{schrep "crefparts" (1,10)(2,20)(3,50)}
schrep "crefparts" (1,10)(2,20)(3,20)

pagename "APD_SC_SCH"
version 1
lowerleft (-8000, 200)
upperright (0, 5000)
xmark "1" -460
xmark "2" -1485
xmark "3" -2485
xmark "4" -3485
xmark "5" -4512
xmark "6" -5512
xmark "7" -6512
xmark "8" -7485
ymark "A" 990
ymark "B" 2195
ymark "C" 3317
ymark "D" 4438
{schrep "basenets" (1,20)(2,35)(3,25)}
schrep "basenets" (1,20)(3,25)
schrep "netsbypage" (1,7)(2,15)(3,20)(4,15)(5,21)
schrep "synonyms" (1,15)(2,20)(3,25)(4,21)
{schrep "crefparts" (1,10)(2,20)(3,50)}
schrep "crefparts" (1,10)(2,20)(3,20)

pagename "A SIZE PAGE"
version 1
lowerleft (-3750, 0)
upperright (0, 5000)
xmark "1" -500
xmark "2" -1500
xmark "3" -2500
xmark "4" -3425
ymark "A" 950
ymark "B" 2200
ymark "C" 3350
ymark "D" 4475
excludearea "1" (-1700,0) (0,400)
pagename "B SIZE PAGE"
version 1
lowerleft (-8000, 0)
upperright (0, 5000)
xmark "1" -500
xmark "2" -1500
xmark "3" -2500
xmark "4" -3500
xmark "5" -4500
xmark "6" -5500
xmark "7" -6500
xmark "8" -7500
ymark "A" 1000
ymark "B" 2200
ymark "C" 3350
ymark "D" 4500
excludearea "1" (-2550,0) (0,400)
pagename "C SIZE PAGE"
version 1
lowerleft (-10650, 100)
upperright (-75, 8175)
xmark "1" -750
xmark "2" -2000
xmark "3" -3350
xmark "4" -4700
xmark "5" -6050
xmark "6" -7400
xmark "7" -8750
xmark "8" -10100
ymark "A" 675
ymark "B" 2025
ymark "C" 3375
ymark "D" 4750
ymark "E" 6075
ymark "F" 7525
excludearea "1" (-4050,100) (-75,900)
excludearea "2" (-2850,7800) (-75,8175)
pagename "D SIZE PAGE"
version 1
lowerleft (-14625, 250)
upperright (1875, 10750)
xmark "1" 950
xmark "2" -1075
xmark "3" -3200
xmark "4" -5300
xmark "5" -7450
xmark "6" -9575
xmark "7" -11700
xmark "8" -13725
ymark "A" 1625
ymark "B" 4200
ymark "C" 6825
ymark "D" 9475
excludearea "1" (-2250,250) (1875,1100)
excludearea "2" (-1600,10150) (1875,10750)
pagename "E SIZE PAGE"
version 1
lowerleft (-10700, -8200)
upperright (10750, 7750)
xmark "1" 9600
xmark "2" 6850
xmark "3" 4150
xmark "4" 1400
xmark "5" -1350
xmark "6" -4125
xmark "7" -6875
xmark "8" -9650
ymark "A" -7700
ymark "B" -5500
ymark "C" -3450
ymark "D" -1300
ymark "E" 800
ymark "F" 2950
ymark "G" 5100
ymark "H" 7150
excludearea "1" (6800,-8200) (10750,-7350)
excludearea "2" (6900,7400) (10750,7750)
pagename "F SIZE PAGE"
version 1
lowerleft (-9725, -6725)
upperright (9750, 6725)
xmark "1" 8825
xmark "2" 6250
xmark "3" 3750
xmark "4" 1250
xmark "5" -1300
xmark "6" -3750
xmark "7" -6200
xmark "8" -8800
ymark "A" -5800
ymark "B" -3400
ymark "C" -1050
ymark "D" 1250
ymark "E" 3575
ymark "F" 5800
excludearea "1" (5700,-6725) (9750,-5800)
excludearea "2" (5900,6350) (9750,6725)
pagename "CADENCE A SIZE PAGE"
version 1
lowerleft (-3750, 0)
upperright (0, 5000)
xmark "1" -500
xmark "2" -1500
xmark "3" -2500
xmark "4" -3425
ymark "A" 950
ymark "B" 2200
ymark "C" 3350
ymark "D" 4475
excludearea "1" (-3750,0) (0,450)
pagename "CADENCE A SIZE PAGE"
version 2
lowerleft (-3750, 0)
upperright (0, 5000)
xmark "1" -500
xmark "2" -1500
xmark "3" -2500
xmark "4" -3425
ymark "A" 950
ymark "B" 2200
ymark "C" 3350
ymark "D" 4475
excludearea "1" (-3750,0) (0,450)
pagename "CADENCE B SIZE PAGE"
version 1
lowerleft (-8000, 0)
upperright (0, 5000)
xmark "1" -500
xmark "2" -1500
xmark "3" -2500
xmark "4" -3500
xmark "5" -4500
xmark "6" -5500
xmark "7" -6500
xmark "8" -7500
ymark "A" 1000
ymark "B" 2200
ymark "C" 3350
ymark "D" 4500
excludearea "1" (-8000,0) (0,400)
pagename "CADENCE B SIZE PAGE"
version 2
lowerleft (-8000, 0)
upperright (0, 5000)
xmark "1" -500
xmark "2" -1500
xmark "3" -2500
xmark "4" -3500
xmark "5" -4500
xmark "6" -5500
xmark "7" -6500
xmark "8" -7500
ymark "A" 1000
ymark "B" 2200
ymark "C" 3350
ymark "D" 4500
excludearea "1" (-8000,0) (0,400)
pagename "CADENCE B SIZE PAGE"
version 3
lowerleft (-8000, 0)
upperright (0, 5000)
xmark "1" -500
xmark "2" -1500
xmark "3" -2500
xmark "4" -3500
xmark "5" -4500
xmark "6" -5500
xmark "7" -6500
xmark "8" -7500
ymark "A" 1000
ymark "B" 2200
ymark "C" 3350
ymark "D" 4500
excludearea "1" (-8000,0) (0,1600)
excludearea "2" (-3050,4600) (0,5000)
pagename "VALID A SIZE PAGE"
version 1
lowerleft (-3750, 0)
upperright (0, 5000)
xmark "1" -500
xmark "2" -1500
xmark "3" -2500
xmark "4" -3425
ymark "A" 950
ymark "B" 2200
ymark "C" 3350
ymark "D" 4475
excludearea "1" (-3750,0) (0,400)
pagename "VALID A SIZE PAGE"
version 2
lowerleft (-3750, 0)
upperright (0, 5000)
xmark "1" -500
xmark "2" -1500
xmark "3" -2500
xmark "4" -3425
ymark "A" 950
ymark "B" 2200
ymark "C" 3350
ymark "D" 4475
excludearea "1" (-3750,0) (0,400)
pagename "VALID B SIZE PAGE"
version 1
lowerleft (-8000, 0)
upperright (0, 5000)
xmark "1" -500
xmark "2" -1500
xmark "3" -2500
xmark "4" -3500
xmark "5" -4500
xmark "6" -5500
xmark "7" -6500
xmark "8" -7500
ymark "A" 1000
ymark "B" 2200
ymark "C" 3350
ymark "D" 4500
excludearea "1" (-8000,0) (0,400)
pagename "VALID B SIZE PAGE"
version 2
lowerleft (-8000, 0)
upperright (0, 5000)
xmark "1" -500
xmark "2" -1500
xmark "3" -2500
xmark "4" -3500
xmark "5" -4500
xmark "6" -5500
xmark "7" -6500
xmark "8" -7500
ymark "A" 1000
ymark "B" 2200
ymark "C" 3350
ymark "D" 4500
excludearea "1" (-8000,0) (0,400)
pagename "VALID B SIZE PAGE"
version 3
lowerleft (-8000, 0)
upperright (0, 5000)
xmark "1" -500
xmark "2" -1500
xmark "3" -2500
xmark "4" -3500
xmark "5" -4500
xmark "6" -5500
xmark "7" -6500
xmark "8" -7500
ymark "A" 1000
ymark "B" 2200
ymark "C" 3350
ymark "D" 4500
excludearea "1" (-8000,0) (0,1600)
excludearea "2" (-3050,4600) (0,5000)
pagename "BPAGE"
version 1
lowerleft(-7800,225)
upperright(-125,4825)
xmark "8" -7500
xmark "7" -6500
xmark "6" -5500
xmark "5" -4500
xmark "4" -3500
xmark "3" -2500
xmark "2" -1500
xmark "1" -500
ymark "A" 975
ymark "B" 2175
ymark "C" 3300
ymark "D" 4475
{schrep "basenets" (1,20)(2,35)(3,25)}
schrep "basenets" (1,20)(3,25)
schrep "netsbypage" (1,7)(2,15)(3,20)(4,15)(5,21)
schrep "synonyms" (1,15)(2,20)(3,25)(4,21)
{schrep "crefparts" (1,10)(2,20)(3,50)}
schrep "crefparts" (1,10)(2,20)(3,20)

pagename "BPAGE_APD"
lowerleft(-7800,225)
upperright(-125,4825)
xmark "8" -7500
xmark "7" -6500
xmark "6" -5500
xmark "5" -4500
xmark "4" -3500
xmark "3" -2500
xmark "2" -1500
xmark "1" -500
ymark "A" 975
ymark "B" 2175
ymark "C" 3300
ymark "D" 4475
pagenumber (-375,50)
{schrep "basenets" (1,20)(2,35)(3,25)}
schrep "basenets" (1,20)(3,25)
schrep "netsbypage" (1,7)(2,15)(3,20)(4,15)(5,21)
schrep "synonyms" (1,15)(2,20)(3,25)(4,21)
{schrep "crefparts" (1,10)(2,20)(3,50)}
schrep "crefparts" (1,10)(2,20)(3,20)

pagename "BPAGE_CONFIDENTIAL"
lowerleft(-7800,225)
upperright(-125,4825)
xmark "8" -7500
xmark "7" -6500
xmark "6" -5500
xmark "5" -4500
xmark "4" -3500
xmark "3" -2500
xmark "2" -1500
xmark "1" -500
ymark "A" 975
ymark "B" 2175
ymark "C" 3300
ymark "D" 4475
{schrep "basenets" (1,20)(2,35)(3,25)}
schrep "basenets" (1,20)(3,25)
schrep "netsbypage" (1,7)(2,15)(3,20)(4,15)(5,21)
schrep "synonyms" (1,15)(2,20)(3,25)(4,21)
{schrep "crefparts" (1,10)(2,20)(3,50)}
schrep "crefparts" (1,10)(2,20)(3,20)

pagename "BPAGE_MR266"
lowerleft(-7800,225)
upperright(-125,4825)
xmark "8" -7500
xmark "7" -6500
xmark "6" -5500
xmark "5" -4500
xmark "4" -3500
xmark "3" -2500
xmark "2" -1500
xmark "1" -500
ymark "A" 975
ymark "B" 2175
ymark "C" 3300
ymark "D" 4475
{schrep "basenets" (1,20)(2,35)(3,25)}
schrep "basenets" (1,20)(3,25)
schrep "netsbypage" (1,7)(2,15)(3,20)(4,15)(5,21)
schrep "synonyms" (1,15)(2,20)(3,25)(4,21)
{schrep "crefparts" (1,10)(2,20)(3,50)}
schrep "crefparts" (1,10)(2,20)(3,20)

pagename "BPAGE_PCG"
lowerleft(-7800,225)
upperright(-125,4825)
xmark "8" -7500
xmark "7" -6500
xmark "6" -5500
xmark "5" -4500
xmark "4" -3500
xmark "3" -2500
xmark "2" -1500
xmark "1" -500
ymark "A" 975
ymark "B" 2175
ymark "C" 3300
ymark "D" 4475
{schrep "basenets" (1,20)(2,35)(3,25)}
schrep "basenets" (1,20)(3,25)
schrep "netsbypage" (1,7)(2,15)(3,20)(4,15)(5,21)
schrep "synonyms" (1,15)(2,20)(3,25)(4,21)
{schrep "crefparts" (1,10)(2,20)(3,50)}
schrep "crefparts" (1,10)(2,20)(3,20)

pagename "BPAGE_PF400"
lowerleft(-7800,225)
upperright(-125,4825)
xmark "8" -7500
xmark "7" -6500
xmark "6" -5500
xmark "5" -4500
xmark "4" -3500
xmark "3" -2500
xmark "2" -1500
xmark "1" -500
ymark "A" 975
ymark "B" 2175
ymark "C" 3300
ymark "D" 4475
{schrep "basenets" (1,20)(2,35)(3,25)}
schrep "basenets" (1,20)(3,25)
schrep "netsbypage" (1,7)(2,15)(3,20)(4,15)(5,21)
schrep "synonyms" (1,15)(2,20)(3,25)(4,21)
{schrep "crefparts" (1,10)(2,20)(3,50)}
schrep "crefparts" (1,10)(2,20)(3,20)

pagename "BPAGE_R_SECRET"
lowerleft(-7800,225)
upperright(-125,4825)
xmark "8" -7500
xmark "7" -6500
xmark "6" -5500
xmark "5" -4500
xmark "4" -3500
xmark "3" -2500
xmark "2" -1500
xmark "1" -500
ymark "A" 975
ymark "B" 2175
ymark "C" 3300
ymark "D" 4475
{schrep "basenets" (1,20)(2,35)(3,25)}
schrep "basenets" (1,20)(3,25)
schrep "netsbypage" (1,7)(2,15)(3,20)(4,15)(5,21)
schrep "synonyms" (1,15)(2,20)(3,25)(4,21)
{schrep "crefparts" (1,10)(2,20)(3,50)}
schrep "crefparts" (1,10)(2,20)(3,20)

pagename "BPAGE_SECRET"
lowerleft(-7800,225)
upperright(-125,4825)
xmark "8" -7500
xmark "7" -6500
xmark "6" -5500
xmark "5" -4500
xmark "4" -3500
xmark "3" -2500
xmark "2" -1500
xmark "1" -500
ymark "A" 975
ymark "B" 2175
ymark "C" 3300
ymark "D" 4475
{schrep "basenets" (1,20)(2,35)(3,25)}
schrep "basenets" (1,20)(3,25)
schrep "netsbypage" (1,7)(2,15)(3,20)(4,15)(5,21)
schrep "synonyms" (1,15)(2,20)(3,25)(4,21)
{schrep "crefparts" (1,10)(2,20)(3,50)}
schrep "crefparts" (1,10)(2,20)(3,20)

pagename "BPAGE_SRP"
lowerleft(-7800,225)
upperright(-125,4825)
xmark "8" -7500
xmark "7" -6500
xmark "6" -5500
xmark "5" -4500
xmark "4" -3500
xmark "3" -2500
xmark "2" -1500
xmark "1" -500
ymark "A" 975
ymark "B" 2175
ymark "C" 3300
ymark "D" 4475
{schrep "basenets" (1,20)(2,35)(3,25)}
schrep "basenets" (1,20)(3,25)
schrep "netsbypage" (1,7)(2,15)(3,20)(4,15)(5,21)
schrep "synonyms" (1,15)(2,20)(3,25)(4,21)
{schrep "crefparts" (1,10)(2,20)(3,50)}
schrep "crefparts" (1,10)(2,20)(3,20)

pagename "BPAGE_TOPSECRET"
lowerleft(-7800,225)
upperright(-125,4825)
xmark "8" -7500
xmark "7" -6500
xmark "6" -5500
xmark "5" -4500
xmark "4" -3500
xmark "3" -2500
xmark "2" -1500
xmark "1" -500
ymark "A" 975
ymark "B" 2175
ymark "C" 3300
ymark "D" 4475
{schrep "basenets" (1,20)(2,35)(3,25)}
schrep "basenets" (1,20)(3,25)
schrep "netsbypage" (1,7)(2,15)(3,20)(4,15)(5,21)
schrep "synonyms" (1,15)(2,20)(3,25)(4,21)
{schrep "crefparts" (1,10)(2,20)(3,50)}
schrep "crefparts" (1,10)(2,20)(3,20)

pagename "BPAGE_WS400"
lowerleft(-7800,225)
upperright(-125,4825)
xmark "8" -7500
xmark "7" -6500
xmark "6" -5500
xmark "5" -4500
xmark "4" -3500
xmark "3" -2500
xmark "2" -1500
xmark "1" -500
ymark "A" 975
ymark "B" 2175
ymark "C" 3300
ymark "D" 4475
{schrep "basenets" (1,20)(2,35)(3,25)}
schrep "basenets" (1,20)(3,25)
schrep "netsbypage" (1,7)(2,15)(3,20)(4,15)(5,21)
schrep "synonyms" (1,15)(2,20)(3,25)(4,21)
{schrep "crefparts" (1,10)(2,20)(3,50)}
schrep "crefparts" (1,10)(2,20)(3,20)

pagename "INTELBPAGE"
lowerleft(-7800,225)
upperright(-125,4825)
xmark "8" -7500
xmark "7" -6500
xmark "6" -5500
xmark "5" -4500
xmark "4" -3500
xmark "3" -2500
xmark "2" -1500
xmark "1" -500
ymark "A" 975
ymark "B" 2175
ymark "C" 3300
ymark "D" 4475
{schrep "basenets" (1,20)(2,35)(3,25)}
schrep "basenets" (1,20)(3,25)
schrep "netsbypage" (1,7)(2,15)(3,20)(4,15)(5,21)
schrep "synonyms" (1,15)(2,20)(3,25)(4,21)
{schrep "crefparts" (1,10)(2,20)(3,50)}
schrep "crefparts" (1,10)(2,20)(3,20)
pagename "BPAGE_DUP"
lowerleft(-7800,225)
upperright(-125,4825)
xmark "8" -7500
xmark "7" -6500
xmark "6" -5500
xmark "5" -4500
xmark "4" -3500
xmark "3" -2500
xmark "2" -1500
xmark "1" -500
ymark "A" 975
ymark "B" 2175
ymark "C" 3300
ymark "D" 4475
{schrep "basenets" (1,20)(2,35)(3,25)}
{schrep "basenets" (1,20)(3,21)}
schrep "basenets" (1,20)(3,8)
{schrep "netsbypage" (1,7)(2,15)(3,20)(4,15)(5,21)}
schrep "netsbypage" (1,5)(2,20)(5,21)
schrep "synonyms" (1,15)(2,20)(3,25)(4,21)
{schrep "crefparts" (1,10)(2,20)(3,50)}
schrep "crefparts" (1,7)(2,20)(3,10)

BIFLAG "FLAG" VERSION 9
BIFLAG "FLAG" VERSION 10
BIFLAG "FLAG" VERSION 11
BIFLAG "FLAG" VERSION 12
BIFLAG "IOPORT" VERSION 1
BIFLAG "OFFPAGE" VERSION 3
BIFLAG "OFFPAGE" VERSION 6
BIFLAG "OFFPAGE_BI" VERSION 1
BIFLAG "OFFPAGE_IN" VERSION 1
BIFLAG "OFFPAGE_OUT" VERSION 1
INFLAG "FLAG" VERSION 1
INFLAG "FLAG" VERSION 2
INFLAG "FLAG" VERSION 3
INFLAG "FLAG" VERSION 4
INFLAG "INPORT" VERSION 1
INFLAG "OFFPAGE" VERSION 1
INFLAG "OFFPAGE" VERSION 1
INFLAG "OFFPAGE" VERSION 4
OUTFLAG "FLAG" VERSION 5
OUTFLAG "FLAG" VERSION 6
OUTFLAG "FLAG" VERSION 7
OUTFLAG "FLAG" VERSION 8
OUTFLAG "OFFPAGE" VERSION 2
OUTFLAG "OFFPAGE" VERSION 5
OUTFLAG "OUTPORT" VERSION 1
BIFLAG "OFFPAG_BI" VERSION 1
BIFLAG "OFFPAG_IN" VERSION 1
BIFLAG "OFFPAG_OUT" VERSION 1
